(kicad_pcb
	(version 20260206)
	(generator "pcbnew")
	(generator_version "10.0")
	(general
		(thickness 1.6)
		(legacy_teardrops no)
	)
	(paper "A4")
	(title_block
		(title "pdpb — Lightning_PDPB_BRD.brd")
		(comment 1 "Lightning (Wiwynn / Facebook NVMe JBOF) / footprints 1069-1073 of 1140")
	)
	(layers
		(0 "F.Cu" signal "TOP")
		(4 "In1.Cu" signal "L2GND")
		(6 "In2.Cu" signal "L3")
		(8 "In3.Cu" signal "L4VCC")
		(10 "In4.Cu" signal "L5VCC")
		(12 "In5.Cu" signal "L6")
		(14 "In6.Cu" signal "L7GND")
		(2 "B.Cu" signal "BOTTOM")
		(9 "F.Adhes" user "F.Adhesive")
		(11 "B.Adhes" user "B.Adhesive")
		(13 "F.Paste" user "Package Geometry/Pastemask Top")
		(15 "B.Paste" user "Package Geometry/Pastemask Bottom")
		(5 "F.SilkS" user "Ref Des/Silkscreen Top")
		(7 "B.SilkS" user "Ref Des/Silkscreen Bottom")
		(1 "F.Mask" user "Board Geometry/Soldermask Top")
		(3 "B.Mask" user "Board Geometry/Soldermask Bottom")
		(17 "Dwgs.User" user "User.Drawings")
		(19 "Cmts.User" user "User.Comments")
		(21 "Eco1.User" user "User.Eco1")
		(23 "Eco2.User" user "User.Eco2")
		(25 "Edge.Cuts" user "Board Geometry/Outline")
		(27 "Margin" user)
		(31 "F.CrtYd" user "Package Geometry/Place Bound Top")
		(29 "B.CrtYd" user "Package Geometry/Place Bound Bottom")
		(35 "F.Fab" user "Ref Des/Assembly Top")
		(33 "B.Fab" user "Ref Des/Assembly Bottom")
	)
	(footprint ""
		(layer "F.Cu")
		(at 234.061 -349.631 -90)
		(property "Reference" "R9450"
			(at 0 0 270)
			(layer "F.SilkS")
			(hide yes)
			(effects
				(font
					(size 1.27 1.27)
				)
			)
		)
		(property "Value" "100R2J-2-GP"
			(at 0.064008 -3.993896 270)
			(unlocked yes)
			(layer "F.Fab")
			(hide yes)
			(effects
				(font
					(size 1.016 1.016)
					(thickness 0.1524)
				)
			)
		)
		(property "Device Type" "R402H14"
			(at 0.064008 -5.517896 270)
			(unlocked yes)
			(layer "F.Fab")
			(hide yes)
			(effects
				(font
					(size 1.016 1.016)
					(thickness 0.1524)
				)
			)
		)
		(duplicate_pad_numbers_are_jumpers no)
		(fp_line
			(start -0.508 -0.9398)
			(end -0.508 0.9398)
			(stroke
				(width 0.1524)
				(type default)
			)
			(layer "F.SilkS")
		)
		(fp_line
			(start 0.508 -0.9398)
			(end -0.508 -0.9398)
			(stroke
				(width 0.1524)
				(type default)
			)
			(layer "F.SilkS")
		)
		(fp_rect
			(start -0.508 0.9398)
			(end 0.508 -0.9398)
			(stroke
				(width 0)
				(type default)
			)
			(fill no)
			(layer "F.CrtYd")
		)
		(fp_rect
			(start -0.508 0.9398)
			(end 0.508 -0.9398)
			(stroke
				(width 0)
				(type default)
			)
			(fill no)
			(layer "F.Fab")
		)
		(pad "1" smd custom
			(at 0 -0.4445 270)
			(size 0.1397 0.1397)
			(layers "F.Cu" "F.Mask" "F.Paste")
			(net "P3V3")
			(options
				(clearance outline)
				(anchor circle)
			)
			(primitives
				(gr_poly
					(pts
						(arc
							(start -0.1778 -0.2794)
							(mid -0.249642 -0.249642)
							(end -0.2794 -0.1778)
						)
						(arc
							(start -0.2794 0.1778)
							(mid -0.249642 0.249642)
							(end -0.1778 0.2794)
						)
						(arc
							(start 0.1778 0.2794)
							(mid 0.249642 0.249642)
							(end 0.2794 0.1778)
						)
						(arc
							(start 0.2794 -0.1778)
							(mid 0.249642 -0.249642)
							(end 0.1778 -0.2794)
						)
					)
					(width 0)
					(fill yes)
				)
			)
		)
		(pad "2" smd custom
			(at 0 0.4445 270)
			(size 0.1397 0.1397)
			(layers "F.Cu" "F.Mask" "F.Paste")
			(net "DRV_ACT_1")
			(options
				(clearance outline)
				(anchor circle)
			)
			(primitives
				(gr_poly
					(pts
						(arc
							(start -0.1778 -0.2794)
							(mid -0.249642 -0.249642)
							(end -0.2794 -0.1778)
						)
						(arc
							(start -0.2794 0.1778)
							(mid -0.249642 0.249642)
							(end -0.1778 0.2794)
						)
						(arc
							(start 0.1778 0.2794)
							(mid 0.249642 0.249642)
							(end 0.2794 0.1778)
						)
						(arc
							(start 0.2794 -0.1778)
							(mid 0.249642 -0.249642)
							(end 0.1778 -0.2794)
						)
					)
					(width 0)
					(fill yes)
				)
			)
		)
	)
	(footprint ""
		(layer "F.Cu")
		(at 81.661 -356.9716 -90)
		(property "Reference" "SR992"
			(at 0 0 270)
			(layer "F.SilkS")
			(hide yes)
			(effects
				(font
					(size 1.27 1.27)
				)
			)
		)
		(property "Value" "2KR2F-3-GP"
			(at 0.064008 -3.993896 270)
			(unlocked yes)
			(layer "F.Fab")
			(hide yes)
			(effects
				(font
					(size 1.016 1.016)
					(thickness 0.1524)
				)
			)
		)
		(property "Device Type" "R402H16"
			(at 0.064008 -5.517896 270)
			(unlocked yes)
			(layer "F.Fab")
			(hide yes)
			(effects
				(font
					(size 1.016 1.016)
					(thickness 0.1524)
				)
			)
		)
		(duplicate_pad_numbers_are_jumpers no)
		(fp_line
			(start -0.508 -0.9398)
			(end -0.508 0.9398)
			(stroke
				(width 0.1524)
				(type default)
			)
			(layer "F.SilkS")
		)
		(fp_line
			(start 0.508 -0.9398)
			(end -0.508 -0.9398)
			(stroke
				(width 0.1524)
				(type default)
			)
			(layer "F.SilkS")
		)
		(fp_rect
			(start -0.508 0.9398)
			(end 0.508 -0.9398)
			(stroke
				(width 0)
				(type default)
			)
			(fill no)
			(layer "F.CrtYd")
		)
		(fp_rect
			(start -0.508 0.9398)
			(end 0.508 -0.9398)
			(stroke
				(width 0)
				(type default)
			)
			(fill no)
			(layer "F.Fab")
		)
		(pad "1" smd custom
			(at 0 -0.4445 270)
			(size 0.1397 0.1397)
			(layers "F.Cu" "F.Mask" "F.Paste")
			(net "P3V3")
			(options
				(clearance outline)
				(anchor circle)
			)
			(primitives
				(gr_poly
					(pts
						(arc
							(start -0.1778 -0.2794)
							(mid -0.249642 -0.249642)
							(end -0.2794 -0.1778)
						)
						(arc
							(start -0.2794 0.1778)
							(mid -0.249642 0.249642)
							(end -0.1778 0.2794)
						)
						(arc
							(start 0.1778 0.2794)
							(mid 0.249642 0.249642)
							(end 0.2794 0.1778)
						)
						(arc
							(start 0.2794 -0.1778)
							(mid 0.249642 -0.249642)
							(end 0.1778 -0.2794)
						)
					)
					(width 0)
					(fill yes)
				)
			)
		)
		(pad "2" smd custom
			(at 0 0.4445 270)
			(size 0.1397 0.1397)
			(layers "F.Cu" "F.Mask" "F.Paste")
			(net "SDA_DR2")
			(options
				(clearance outline)
				(anchor circle)
			)
			(primitives
				(gr_poly
					(pts
						(arc
							(start -0.1778 -0.2794)
							(mid -0.249642 -0.249642)
							(end -0.2794 -0.1778)
						)
						(arc
							(start -0.2794 0.1778)
							(mid -0.249642 0.249642)
							(end -0.1778 0.2794)
						)
						(arc
							(start 0.1778 0.2794)
							(mid 0.249642 0.249642)
							(end 0.2794 0.1778)
						)
						(arc
							(start 0.2794 -0.1778)
							(mid 0.249642 -0.249642)
							(end 0.1778 -0.2794)
						)
					)
					(width 0)
					(fill yes)
				)
			)
		)
	)
	(footprint ""
		(layer "F.Cu")
		(at 230.251 -439.166 180)
		(property "Reference" "R9891"
			(at 0 0 180)
			(layer "F.SilkS")
			(hide yes)
			(effects
				(font
					(size 1.27 1.27)
				)
			)
		)
		(property "Value" "15KR2F-GP"
			(at 0.064008 -3.993896 180)
			(unlocked yes)
			(layer "F.Fab")
			(hide yes)
			(effects
				(font
					(size 1.016 1.016)
					(thickness 0.1524)
				)
			)
		)
		(property "Device Type" "R402H16"
			(at 0.064008 -5.517896 180)
			(unlocked yes)
			(layer "F.Fab")
			(hide yes)
			(effects
				(font
					(size 1.016 1.016)
					(thickness 0.1524)
				)
			)
		)
		(duplicate_pad_numbers_are_jumpers no)
		(fp_line
			(start 0.508 -0.9398)
			(end -0.508 -0.9398)
			(stroke
				(width 0.1524)
				(type default)
			)
			(layer "F.SilkS")
		)
		(fp_line
			(start -0.508 -0.9398)
			(end -0.508 0.9398)
			(stroke
				(width 0.1524)
				(type default)
			)
			(layer "F.SilkS")
		)
		(fp_rect
			(start -0.508 0.9398)
			(end 0.508 -0.9398)
			(stroke
				(width 0)
				(type default)
			)
			(fill no)
			(layer "F.CrtYd")
		)
		(fp_rect
			(start -0.508 0.9398)
			(end 0.508 -0.9398)
			(stroke
				(width 0)
				(type default)
			)
			(fill no)
			(layer "F.Fab")
		)
		(pad "1" smd custom
			(at 0 -0.4445 180)
			(size 0.1397 0.1397)
			(layers "F.Cu" "F.Mask" "F.Paste")
			(net "TPS53312_P3V3_PG")
			(options
				(clearance outline)
				(anchor circle)
			)
			(primitives
				(gr_poly
					(pts
						(arc
							(start -0.1778 -0.2794)
							(mid -0.249642 -0.249642)
							(end -0.2794 -0.1778)
						)
						(arc
							(start -0.2794 0.1778)
							(mid -0.249642 0.249642)
							(end -0.1778 0.2794)
						)
						(arc
							(start 0.1778 0.2794)
							(mid 0.249642 0.249642)
							(end 0.2794 0.1778)
						)
						(arc
							(start 0.2794 -0.1778)
							(mid 0.249642 -0.249642)
							(end 0.1778 -0.2794)
						)
					)
					(width 0)
					(fill yes)
				)
			)
		)
		(pad "2" smd custom
			(at 0 0.4445 180)
			(size 0.1397 0.1397)
			(layers "F.Cu" "F.Mask" "F.Paste")
			(net "GND")
			(options
				(clearance outline)
				(anchor circle)
			)
			(primitives
				(gr_poly
					(pts
						(arc
							(start -0.1778 -0.2794)
							(mid -0.249642 -0.249642)
							(end -0.2794 -0.1778)
						)
						(arc
							(start -0.2794 0.1778)
							(mid -0.249642 0.249642)
							(end -0.1778 0.2794)
						)
						(arc
							(start 0.1778 0.2794)
							(mid 0.249642 0.249642)
							(end 0.2794 0.1778)
						)
						(arc
							(start 0.2794 -0.1778)
							(mid 0.249642 -0.249642)
							(end 0.1778 -0.2794)
						)
					)
					(width 0)
					(fill yes)
				)
			)
		)
	)
	(footprint ""
		(layer "F.Cu")
		(at 28.8671 -300.5201 180)
		(property "Reference" "R9828"
			(at 0 0 180)
			(layer "F.SilkS")
			(hide yes)
			(effects
				(font
					(size 1.27 1.27)
				)
			)
		)
		(property "Value" "47KR2J-2-GP"
			(at 0.064008 -3.993896 180)
			(unlocked yes)
			(layer "F.Fab")
			(hide yes)
			(effects
				(font
					(size 1.016 1.016)
					(thickness 0.1524)
				)
			)
		)
		(property "Device Type" "R402H16"
			(at 0.064008 -5.517896 180)
			(unlocked yes)
			(layer "F.Fab")
			(hide yes)
			(effects
				(font
					(size 1.016 1.016)
					(thickness 0.1524)
				)
			)
		)
		(duplicate_pad_numbers_are_jumpers no)
		(fp_line
			(start 0.508 -0.9398)
			(end -0.508 -0.9398)
			(stroke
				(width 0.1524)
				(type default)
			)
			(layer "F.SilkS")
		)
		(fp_line
			(start -0.508 -0.9398)
			(end -0.508 0.9398)
			(stroke
				(width 0.1524)
				(type default)
			)
			(layer "F.SilkS")
		)
		(fp_rect
			(start -0.508 0.9398)
			(end 0.508 -0.9398)
			(stroke
				(width 0)
				(type default)
			)
			(fill no)
			(layer "F.CrtYd")
		)
		(fp_rect
			(start -0.508 0.9398)
			(end 0.508 -0.9398)
			(stroke
				(width 0)
				(type default)
			)
			(fill no)
			(layer "F.Fab")
		)
		(pad "1" smd custom
			(at 0 -0.4445 180)
			(size 0.1397 0.1397)
			(layers "F.Cu" "F.Mask" "F.Paste")
			(net "P12V")
			(options
				(clearance outline)
				(anchor circle)
			)
			(primitives
				(gr_poly
					(pts
						(arc
							(start -0.1778 -0.2794)
							(mid -0.249642 -0.249642)
							(end -0.2794 -0.1778)
						)
						(arc
							(start -0.2794 0.1778)
							(mid -0.249642 0.249642)
							(end -0.1778 0.2794)
						)
						(arc
							(start 0.1778 0.2794)
							(mid 0.249642 0.249642)
							(end 0.2794 0.1778)
						)
						(arc
							(start 0.2794 -0.1778)
							(mid 0.249642 -0.249642)
							(end 0.1778 -0.2794)
						)
					)
					(width 0)
					(fill yes)
				)
			)
		)
		(pad "2" smd custom
			(at 0 0.4445 180)
			(size 0.1397 0.1397)
			(layers "F.Cu" "F.Mask" "F.Paste")
			(net "P12V_MOST7_GATE")
			(options
				(clearance outline)
				(anchor circle)
			)
			(primitives
				(gr_poly
					(pts
						(arc
							(start -0.1778 -0.2794)
							(mid -0.249642 -0.249642)
							(end -0.2794 -0.1778)
						)
						(arc
							(start -0.2794 0.1778)
							(mid -0.249642 0.249642)
							(end -0.1778 0.2794)
						)
						(arc
							(start 0.1778 0.2794)
							(mid 0.249642 0.249642)
							(end 0.2794 0.1778)
						)
						(arc
							(start 0.2794 -0.1778)
							(mid 0.249642 -0.249642)
							(end 0.1778 -0.2794)
						)
					)
					(width 0)
					(fill yes)
				)
			)
		)
	)
	(footprint ""
		(layer "F.Cu")
		(at 91.059 -24.511)
		(property "Reference" "U53"
			(at 0 0 0)
			(layer "F.SilkS")
			(hide yes)
			(effects
				(font
					(size 1.27 1.27)
				)
			)
		)
		(property "Value" "ADS1015IDGSR-GP"
			(at 0 -11.1252 0)
			(unlocked yes)
			(layer "F.Fab")
			(hide yes)
			(effects
				(font
					(size 1.016 1.016)
					(thickness 0.1524)
				)
			)
		)
		(property "Device Type" "MSOP10H44"
			(at 0 -12.6492 0)
			(unlocked yes)
			(layer "F.Fab")
			(hide yes)
			(effects
				(font
					(size 1.016 1.016)
					(thickness 0.1524)
				)
			)
		)
		(duplicate_pad_numbers_are_jumpers no)
		(fp_line
			(start -2.0066 -1.016)
			(end 1.143 -1.016)
			(stroke
				(width 0.1524)
				(type default)
			)
			(layer "F.SilkS")
		)
		(fp_line
			(start -2.0066 1.016)
			(end -2.0066 -1.016)
			(stroke
				(width 0.1524)
				(type default)
			)
			(layer "F.SilkS")
		)
		(fp_line
			(start -1.8288 1.016)
			(end -1.8288 3.048)
			(stroke
				(width 0.508)
				(type default)
			)
			(layer "F.SilkS")
		)
		(fp_line
			(start -1.5748 0)
			(end -1.9558 -0.381)
			(stroke
				(width 0.1524)
				(type default)
			)
			(layer "F.SilkS")
		)
		(fp_line
			(start -1.5748 0)
			(end -1.9558 0.381)
			(stroke
				(width 0.1524)
				(type default)
			)
			(layer "F.SilkS")
		)
		(fp_line
			(start 1.143 -1.016)
			(end 1.143 1.016)
			(stroke
				(width 0.1524)
				(type default)
			)
			(layer "F.SilkS")
		)
		(fp_line
			(start 1.143 1.016)
			(end -2.0066 1.016)
			(stroke
				(width 0.1524)
				(type default)
			)
			(layer "F.SilkS")
		)
		(fp_poly
			(pts
				(xy -2.0828 3.3401) (xy 2.0828 3.3401) (xy 2.0828 -3.3401) (xy -2.0828 -3.3401)
			)
			(stroke
				(width 0)
				(type default)
			)
			(fill no)
			(layer "F.CrtYd")
		)
		(fp_poly
			(pts
				(xy -2.0828 3.3401) (xy 2.0828 3.3401) (xy 2.0828 -3.3401) (xy -2.0828 -3.3401)
			)
			(stroke
				(width 0)
				(type default)
			)
			(fill no)
			(layer "F.Fab")
		)
		(pad "1" smd rect
			(at -0.99949 2.0701)
			(size 0.3048 1.524)
			(layers "F.Cu" "F.Mask" "F.Paste")
			(net "VOL_SEN_ADDR")
		)
		(pad "2" smd rect
			(at -0.50038 2.0701)
			(size 0.3048 1.524)
			(layers "F.Cu" "F.Mask" "F.Paste")
			(net "VOL_SEN_ALERT")
		)
		(pad "3" smd rect
			(at 0 2.0701)
			(size 0.3048 1.524)
			(layers "F.Cu" "F.Mask" "F.Paste")
			(net "GND")
		)
		(pad "4" smd rect
			(at 0.50038 2.0701)
			(size 0.3048 1.524)
			(layers "F.Cu" "F.Mask" "F.Paste")
			(net "P12V_SENSE")
		)
		(pad "5" smd rect
			(at 0.99949 2.0701)
			(size 0.3048 1.524)
			(layers "F.Cu" "F.Mask" "F.Paste")
			(net "P12V_SSD14_SENSE")
		)
		(pad "6" smd rect
			(at 0.99949 -2.0701)
			(size 0.3048 1.524)
			(layers "F.Cu" "F.Mask" "F.Paste")
			(net "P3V3_SENSE")
		)
		(pad "7" smd rect
			(at 0.50038 -2.0701)
			(size 0.3048 1.524)
			(layers "F.Cu" "F.Mask" "F.Paste")
			(net "Net_31")
		)
		(pad "8" smd rect
			(at 0 -2.0701)
			(size 0.3048 1.524)
			(layers "F.Cu" "F.Mask" "F.Paste")
			(net "P3V3")
		)
		(pad "9" smd rect
			(at -0.50038 -2.0701)
			(size 0.3048 1.524)
			(layers "F.Cu" "F.Mask" "F.Paste")
			(net "VOL_SEN_SDA")
		)
		(pad "10" smd rect
			(at -0.99949 -2.0701)
			(size 0.3048 1.524)
			(layers "F.Cu" "F.Mask" "F.Paste")
			(net "VOL_SEN_SCL")
		)
	)
)
